(kicad_pcb
	(version 20260206)
	(generator "pcbnew")
	(generator_version "10.0")
	(general
		(thickness 1.6)
		(legacy_teardrops no)
	)
	(paper "A4")
	(title_block
		(title "01162023_DA0F0TEBIF0_F0T_Expander_BD_F_brd_V02_OCP.brd")
		(comment 1 "Grand Teton / footprints 1908-1915 of 9728")
	)
	(layers
		(0 "F.Cu" signal "TOP")
		(4 "In1.Cu" signal "GND")
		(6 "In2.Cu" signal "VCC")
		(8 "In3.Cu" signal "VCC1")
		(10 "In4.Cu" signal "GND1")
		(12 "In5.Cu" signal "IN1")
		(14 "In6.Cu" signal "GND2")
		(16 "In7.Cu" signal "IN2")
		(18 "In8.Cu" signal "GND3")
		(20 "In9.Cu" signal "IN3")
		(22 "In10.Cu" signal "GND4")
		(24 "In11.Cu" signal "IN4")
		(26 "In12.Cu" signal "GND5")
		(28 "In13.Cu" signal "IN5")
		(30 "In14.Cu" signal "GND6")
		(32 "In15.Cu" signal "IN6")
		(34 "In16.Cu" signal "GND7")
		(2 "B.Cu" signal "BOTTOM")
		(9 "F.Adhes" user "F.Adhesive")
		(11 "B.Adhes" user "B.Adhesive")
		(13 "F.Paste" user "Package Geometry/Pastemask Top")
		(15 "B.Paste" user "Package Geometry/Pastemask Bottom")
		(5 "F.SilkS" user "Ref Des/Silkscreen Top")
		(7 "B.SilkS" user "Ref Des/Silkscreen Bottom")
		(1 "F.Mask" user "Board Geometry/Soldermask Top")
		(3 "B.Mask" user "Board Geometry/Soldermask Bottom")
		(17 "Dwgs.User" user "User.Drawings")
		(19 "Cmts.User" user "User.Comments")
		(21 "Eco1.User" user "User.Eco1")
		(23 "Eco2.User" user "User.Eco2")
		(25 "Edge.Cuts" user "Board Geometry/Outline")
		(27 "Margin" user)
		(31 "F.CrtYd" user "Package Geometry/Place Bound Top")
		(29 "B.CrtYd" user "Package Geometry/Place Bound Bottom")
		(35 "F.Fab" user "Ref Des/Assembly Top")
		(33 "B.Fab" user "Ref Des/Assembly Bottom")
	)
	(footprint ""
		(layer "F.Cu")
		(at 221.695518 -307.137308 90)
		(property "Reference" "PC237"
			(at 0 0 90)
			(layer "F.SilkS")
			(hide yes)
			(effects
				(font
					(size 1.27 1.27)
				)
			)
		)
		(property "Value" ""
			(at 0 0 90)
			(layer "F.Fab")
			(effects
				(font
					(size 1.27 1.27)
				)
			)
		)
		(duplicate_pad_numbers_are_jumpers no)
		(fp_line
			(start 0.7874 -0.4064)
			(end 0.7874 0.4064)
			(stroke
				(width 0.1524)
				(type default)
			)
			(layer "F.SilkS")
		)
		(fp_line
			(start -0.7874 -0.4064)
			(end 0.7874 -0.4064)
			(stroke
				(width 0.1524)
				(type default)
			)
			(layer "F.SilkS")
		)
		(fp_line
			(start 0.7874 0.4064)
			(end -0.7874 0.4064)
			(stroke
				(width 0.1524)
				(type default)
			)
			(layer "F.SilkS")
		)
		(fp_line
			(start -0.7874 0.4064)
			(end -0.7874 -0.4064)
			(stroke
				(width 0.1524)
				(type default)
			)
			(layer "F.SilkS")
		)
		(fp_line
			(start -0.12065 -0.305054)
			(end -0.12065 -0.2794)
			(stroke
				(width 0.1)
				(type default)
			)
			(layer "F.Fab")
		)
		(fp_line
			(start -0.67945 -0.305054)
			(end -0.12065 -0.305054)
			(stroke
				(width 0.1)
				(type default)
			)
			(layer "F.Fab")
		)
		(fp_line
			(start 0.67945 -0.3048)
			(end 0.67945 0.3048)
			(stroke
				(width 0.1)
				(type default)
			)
			(layer "F.Fab")
		)
		(fp_line
			(start 0.12065 -0.3048)
			(end 0.67945 -0.3048)
			(stroke
				(width 0.1)
				(type default)
			)
			(layer "F.Fab")
		)
		(fp_line
			(start 0.12065 -0.2794)
			(end 0.12065 -0.3048)
			(stroke
				(width 0.1)
				(type default)
			)
			(layer "F.Fab")
		)
		(fp_line
			(start -0.12065 -0.2794)
			(end 0.12065 -0.2794)
			(stroke
				(width 0.1)
				(type default)
			)
			(layer "F.Fab")
		)
		(fp_line
			(start 0.120396 0.2794)
			(end -0.12065 0.2794)
			(stroke
				(width 0.1)
				(type default)
			)
			(layer "F.Fab")
		)
		(fp_line
			(start -0.12065 0.2794)
			(end -0.12065 0.3048)
			(stroke
				(width 0.1)
				(type default)
			)
			(layer "F.Fab")
		)
		(fp_line
			(start 0.67945 0.3048)
			(end 0.120396 0.3048)
			(stroke
				(width 0.1)
				(type default)
			)
			(layer "F.Fab")
		)
		(fp_line
			(start 0.120396 0.3048)
			(end 0.120396 0.2794)
			(stroke
				(width 0.1)
				(type default)
			)
			(layer "F.Fab")
		)
		(fp_line
			(start -0.12065 0.3048)
			(end -0.67945 0.3048)
			(stroke
				(width 0.1)
				(type default)
			)
			(layer "F.Fab")
		)
		(fp_line
			(start -0.67945 0.3048)
			(end -0.67945 -0.305054)
			(stroke
				(width 0.1)
				(type default)
			)
			(layer "F.Fab")
		)
		(pad "1" smd circle
			(at -0.40005 0 90)
			(size 0 0)
			(layers "F.Cu" "F.Mask" "F.Paste")
			(net "P1V25_PEX1_VCC")
		)
		(pad "2" smd circle
			(at 0.40005 0 90)
			(size 0 0)
			(layers "F.Cu" "F.Mask" "F.Paste")
			(net "GND")
		)
	)
	(footprint ""
		(layer "F.Cu")
		(at 76.891642 -356.244906 90)
		(property "Reference" "C111"
			(at 0 0 90)
			(layer "F.SilkS")
			(hide yes)
			(effects
				(font
					(size 1.27 1.27)
				)
			)
		)
		(property "Value" ""
			(at 0 0 90)
			(layer "F.Fab")
			(effects
				(font
					(size 1.27 1.27)
				)
			)
		)
		(duplicate_pad_numbers_are_jumpers no)
		(fp_line
			(start 0.299974 -0.150114)
			(end 0.299974 0.150114)
			(stroke
				(width 0.1)
				(type default)
			)
			(layer "F.Fab")
		)
		(fp_line
			(start -0.299974 -0.150114)
			(end 0.299974 -0.150114)
			(stroke
				(width 0.1)
				(type default)
			)
			(layer "F.Fab")
		)
		(fp_line
			(start 0.299974 0.150114)
			(end -0.299974 0.150114)
			(stroke
				(width 0.1)
				(type default)
			)
			(layer "F.Fab")
		)
		(fp_line
			(start -0.299974 0.150114)
			(end -0.299974 -0.150114)
			(stroke
				(width 0.1)
				(type default)
			)
			(layer "F.Fab")
		)
		(pad "1" smd rect
			(at -0.2667 0 90)
			(size 0.3048 0.381)
			(layers "F.Cu" "F.Mask" "F.Paste")
			(net "P5E_PEX0_STN5_TX_DP<88>")
		)
		(pad "2" smd rect
			(at 0.2667 0 90)
			(size 0.3048 0.381)
			(layers "F.Cu" "F.Mask" "F.Paste")
			(net "P5E_PEX0_STN5_TX_C_DP<88>")
		)
	)
	(footprint ""
		(layer "F.Cu")
		(at 361.44327 -277.644352)
		(property "Reference" "PC175"
			(at 0 0 0)
			(layer "F.SilkS")
			(hide yes)
			(effects
				(font
					(size 1.27 1.27)
				)
			)
		)
		(property "Value" ""
			(at 0 0 0)
			(layer "F.Fab")
			(effects
				(font
					(size 1.27 1.27)
				)
			)
		)
		(duplicate_pad_numbers_are_jumpers no)
		(fp_line
			(start -1.524 -0.762)
			(end 1.524 -0.762)
			(stroke
				(width 0.1524)
				(type default)
			)
			(layer "F.SilkS")
		)
		(fp_line
			(start -1.524 0.762)
			(end -1.524 -0.762)
			(stroke
				(width 0.1524)
				(type default)
			)
			(layer "F.SilkS")
		)
		(fp_line
			(start 1.524 -0.762)
			(end 1.524 0.762)
			(stroke
				(width 0.1524)
				(type default)
			)
			(layer "F.SilkS")
		)
		(fp_line
			(start 1.524 0.762)
			(end -1.524 0.762)
			(stroke
				(width 0.1524)
				(type default)
			)
			(layer "F.SilkS")
		)
		(fp_line
			(start -1.1049 -0.724916)
			(end -1.1049 0.724916)
			(stroke
				(width 0.1)
				(type default)
			)
			(layer "F.Fab")
		)
		(fp_line
			(start -1.1049 0.724916)
			(end 1.1049 0.724916)
			(stroke
				(width 0.1)
				(type default)
			)
			(layer "F.Fab")
		)
		(fp_line
			(start 1.1049 -0.724916)
			(end -1.1049 -0.724916)
			(stroke
				(width 0.1)
				(type default)
			)
			(layer "F.Fab")
		)
		(fp_line
			(start 1.1049 0.724916)
			(end 1.1049 -0.724916)
			(stroke
				(width 0.1)
				(type default)
			)
			(layer "F.Fab")
		)
		(pad "1" smd rect
			(at -0.889 0 180)
			(size 1.016 1.27)
			(layers "F.Cu" "F.Mask" "F.Paste")
			(net "SW_P12V_P0V8_PEX3_FLT")
		)
		(pad "2" smd rect
			(at 0.889 0 180)
			(size 1.016 1.27)
			(layers "F.Cu" "F.Mask" "F.Paste")
			(net "GND")
		)
	)
	(footprint ""
		(layer "F.Cu")
		(at 162.374072 -72.766682 90)
		(property "Reference" "PR7065"
			(at 0 0 90)
			(layer "F.SilkS")
			(hide yes)
			(effects
				(font
					(size 1.27 1.27)
				)
			)
		)
		(property "Value" ""
			(at 0 0 90)
			(layer "F.Fab")
			(effects
				(font
					(size 1.27 1.27)
				)
			)
		)
		(duplicate_pad_numbers_are_jumpers no)
		(fp_line
			(start 0.7874 -0.4064)
			(end 0.7874 0.4064)
			(stroke
				(width 0.1524)
				(type default)
			)
			(layer "F.SilkS")
		)
		(fp_line
			(start -0.7874 -0.4064)
			(end 0.7874 -0.4064)
			(stroke
				(width 0.1524)
				(type default)
			)
			(layer "F.SilkS")
		)
		(fp_line
			(start 0.7874 0.4064)
			(end -0.7874 0.4064)
			(stroke
				(width 0.1524)
				(type default)
			)
			(layer "F.SilkS")
		)
		(fp_line
			(start -0.7874 0.4064)
			(end -0.7874 -0.4064)
			(stroke
				(width 0.1524)
				(type default)
			)
			(layer "F.SilkS")
		)
		(fp_line
			(start -0.12065 -0.305054)
			(end -0.12065 -0.2794)
			(stroke
				(width 0.1)
				(type default)
			)
			(layer "F.Fab")
		)
		(fp_line
			(start -0.67945 -0.305054)
			(end -0.12065 -0.305054)
			(stroke
				(width 0.1)
				(type default)
			)
			(layer "F.Fab")
		)
		(fp_line
			(start 0.67945 -0.3048)
			(end 0.67945 0.3048)
			(stroke
				(width 0.1)
				(type default)
			)
			(layer "F.Fab")
		)
		(fp_line
			(start 0.12065 -0.3048)
			(end 0.67945 -0.3048)
			(stroke
				(width 0.1)
				(type default)
			)
			(layer "F.Fab")
		)
		(fp_line
			(start 0.12065 -0.2794)
			(end 0.12065 -0.3048)
			(stroke
				(width 0.1)
				(type default)
			)
			(layer "F.Fab")
		)
		(fp_line
			(start -0.12065 -0.2794)
			(end 0.12065 -0.2794)
			(stroke
				(width 0.1)
				(type default)
			)
			(layer "F.Fab")
		)
		(fp_line
			(start 0.120396 0.2794)
			(end -0.12065 0.2794)
			(stroke
				(width 0.1)
				(type default)
			)
			(layer "F.Fab")
		)
		(fp_line
			(start -0.12065 0.2794)
			(end -0.12065 0.3048)
			(stroke
				(width 0.1)
				(type default)
			)
			(layer "F.Fab")
		)
		(fp_line
			(start 0.67945 0.3048)
			(end 0.120396 0.3048)
			(stroke
				(width 0.1)
				(type default)
			)
			(layer "F.Fab")
		)
		(fp_line
			(start 0.120396 0.3048)
			(end 0.120396 0.2794)
			(stroke
				(width 0.1)
				(type default)
			)
			(layer "F.Fab")
		)
		(fp_line
			(start -0.12065 0.3048)
			(end -0.67945 0.3048)
			(stroke
				(width 0.1)
				(type default)
			)
			(layer "F.Fab")
		)
		(fp_line
			(start -0.67945 0.3048)
			(end -0.67945 -0.305054)
			(stroke
				(width 0.1)
				(type default)
			)
			(layer "F.Fab")
		)
		(pad "1" smd circle
			(at -0.40005 0 90)
			(size 0 0)
			(layers "F.Cu" "F.Mask" "F.Paste")
			(net "P12V_SSD5_CO_MODE")
		)
		(pad "2" smd circle
			(at 0.40005 0 90)
			(size 0 0)
			(layers "F.Cu" "F.Mask" "F.Paste")
			(net "GND")
		)
	)
	(footprint ""
		(layer "F.Cu")
		(at 2.756408 -391.190988 90)
		(property "Reference" "R6757"
			(at 0 0 90)
			(layer "F.SilkS")
			(hide yes)
			(effects
				(font
					(size 1.27 1.27)
				)
			)
		)
		(property "Value" ""
			(at 0 0 90)
			(layer "F.Fab")
			(effects
				(font
					(size 1.27 1.27)
				)
			)
		)
		(duplicate_pad_numbers_are_jumpers no)
		(fp_line
			(start 0.7874 -0.4064)
			(end 0.7874 0.4064)
			(stroke
				(width 0.1524)
				(type default)
			)
			(layer "F.SilkS")
		)
		(fp_line
			(start -0.7874 -0.4064)
			(end 0.7874 -0.4064)
			(stroke
				(width 0.1524)
				(type default)
			)
			(layer "F.SilkS")
		)
		(fp_line
			(start 0.7874 0.4064)
			(end -0.7874 0.4064)
			(stroke
				(width 0.1524)
				(type default)
			)
			(layer "F.SilkS")
		)
		(fp_line
			(start -0.7874 0.4064)
			(end -0.7874 -0.4064)
			(stroke
				(width 0.1524)
				(type default)
			)
			(layer "F.SilkS")
		)
		(fp_line
			(start -0.12065 -0.305054)
			(end -0.12065 -0.2794)
			(stroke
				(width 0.1)
				(type default)
			)
			(layer "F.Fab")
		)
		(fp_line
			(start -0.67945 -0.305054)
			(end -0.12065 -0.305054)
			(stroke
				(width 0.1)
				(type default)
			)
			(layer "F.Fab")
		)
		(fp_line
			(start 0.67945 -0.3048)
			(end 0.67945 0.3048)
			(stroke
				(width 0.1)
				(type default)
			)
			(layer "F.Fab")
		)
		(fp_line
			(start 0.12065 -0.3048)
			(end 0.67945 -0.3048)
			(stroke
				(width 0.1)
				(type default)
			)
			(layer "F.Fab")
		)
		(fp_line
			(start 0.12065 -0.2794)
			(end 0.12065 -0.3048)
			(stroke
				(width 0.1)
				(type default)
			)
			(layer "F.Fab")
		)
		(fp_line
			(start -0.12065 -0.2794)
			(end 0.12065 -0.2794)
			(stroke
				(width 0.1)
				(type default)
			)
			(layer "F.Fab")
		)
		(fp_line
			(start 0.120396 0.2794)
			(end -0.12065 0.2794)
			(stroke
				(width 0.1)
				(type default)
			)
			(layer "F.Fab")
		)
		(fp_line
			(start -0.12065 0.2794)
			(end -0.12065 0.3048)
			(stroke
				(width 0.1)
				(type default)
			)
			(layer "F.Fab")
		)
		(fp_line
			(start 0.67945 0.3048)
			(end 0.120396 0.3048)
			(stroke
				(width 0.1)
				(type default)
			)
			(layer "F.Fab")
		)
		(fp_line
			(start 0.120396 0.3048)
			(end 0.120396 0.2794)
			(stroke
				(width 0.1)
				(type default)
			)
			(layer "F.Fab")
		)
		(fp_line
			(start -0.12065 0.3048)
			(end -0.67945 0.3048)
			(stroke
				(width 0.1)
				(type default)
			)
			(layer "F.Fab")
		)
		(fp_line
			(start -0.67945 0.3048)
			(end -0.67945 -0.305054)
			(stroke
				(width 0.1)
				(type default)
			)
			(layer "F.Fab")
		)
		(pad "1" smd circle
			(at -0.40005 0 90)
			(size 0 0)
			(layers "F.Cu" "F.Mask" "F.Paste")
			(net "RST_BIC_USB_HUB_R_N")
		)
		(pad "2" smd circle
			(at 0.40005 0 90)
			(size 0 0)
			(layers "F.Cu" "F.Mask" "F.Paste")
			(net "BIC_USB_8042_HUB_GRSTZ")
		)
	)
	(footprint ""
		(layer "F.Cu")
		(at 187.35802 -72.766682 90)
		(property "Reference" "PC852"
			(at 0 0 90)
			(layer "F.SilkS")
			(hide yes)
			(effects
				(font
					(size 1.27 1.27)
				)
			)
		)
		(property "Value" ""
			(at 0 0 90)
			(layer "F.Fab")
			(effects
				(font
					(size 1.27 1.27)
				)
			)
		)
		(duplicate_pad_numbers_are_jumpers no)
		(fp_line
			(start 0.7874 -0.4064)
			(end 0.7874 0.4064)
			(stroke
				(width 0.1524)
				(type default)
			)
			(layer "F.SilkS")
		)
		(fp_line
			(start -0.7874 -0.4064)
			(end 0.7874 -0.4064)
			(stroke
				(width 0.1524)
				(type default)
			)
			(layer "F.SilkS")
		)
		(fp_line
			(start 0.7874 0.4064)
			(end -0.7874 0.4064)
			(stroke
				(width 0.1524)
				(type default)
			)
			(layer "F.SilkS")
		)
		(fp_line
			(start -0.7874 0.4064)
			(end -0.7874 -0.4064)
			(stroke
				(width 0.1524)
				(type default)
			)
			(layer "F.SilkS")
		)
		(fp_line
			(start -0.12065 -0.305054)
			(end -0.12065 -0.2794)
			(stroke
				(width 0.1)
				(type default)
			)
			(layer "F.Fab")
		)
		(fp_line
			(start -0.67945 -0.305054)
			(end -0.12065 -0.305054)
			(stroke
				(width 0.1)
				(type default)
			)
			(layer "F.Fab")
		)
		(fp_line
			(start 0.67945 -0.3048)
			(end 0.67945 0.3048)
			(stroke
				(width 0.1)
				(type default)
			)
			(layer "F.Fab")
		)
		(fp_line
			(start 0.12065 -0.3048)
			(end 0.67945 -0.3048)
			(stroke
				(width 0.1)
				(type default)
			)
			(layer "F.Fab")
		)
		(fp_line
			(start 0.12065 -0.2794)
			(end 0.12065 -0.3048)
			(stroke
				(width 0.1)
				(type default)
			)
			(layer "F.Fab")
		)
		(fp_line
			(start -0.12065 -0.2794)
			(end 0.12065 -0.2794)
			(stroke
				(width 0.1)
				(type default)
			)
			(layer "F.Fab")
		)
		(fp_line
			(start 0.120396 0.2794)
			(end -0.12065 0.2794)
			(stroke
				(width 0.1)
				(type default)
			)
			(layer "F.Fab")
		)
		(fp_line
			(start -0.12065 0.2794)
			(end -0.12065 0.3048)
			(stroke
				(width 0.1)
				(type default)
			)
			(layer "F.Fab")
		)
		(fp_line
			(start 0.67945 0.3048)
			(end 0.120396 0.3048)
			(stroke
				(width 0.1)
				(type default)
			)
			(layer "F.Fab")
		)
		(fp_line
			(start 0.120396 0.3048)
			(end 0.120396 0.2794)
			(stroke
				(width 0.1)
				(type default)
			)
			(layer "F.Fab")
		)
		(fp_line
			(start -0.12065 0.3048)
			(end -0.67945 0.3048)
			(stroke
				(width 0.1)
				(type default)
			)
			(layer "F.Fab")
		)
		(fp_line
			(start -0.67945 0.3048)
			(end -0.67945 -0.305054)
			(stroke
				(width 0.1)
				(type default)
			)
			(layer "F.Fab")
		)
		(pad "1" smd circle
			(at -0.40005 0 90)
			(size 0 0)
			(layers "F.Cu" "F.Mask" "F.Paste")
			(net "P12V_SSD6_CO_MODE")
		)
		(pad "2" smd circle
			(at 0.40005 0 90)
			(size 0 0)
			(layers "F.Cu" "F.Mask" "F.Paste")
			(net "GND")
		)
	)
	(footprint ""
		(layer "F.Cu")
		(at 144.149318 -290.595812 -90)
		(property "Reference" "C3238"
			(at 0 0 270)
			(layer "F.SilkS")
			(hide yes)
			(effects
				(font
					(size 1.27 1.27)
				)
			)
		)
		(property "Value" ""
			(at 0 0 270)
			(layer "F.Fab")
			(effects
				(font
					(size 1.27 1.27)
				)
			)
		)
		(duplicate_pad_numbers_are_jumpers no)
		(fp_line
			(start -0.299974 0.150114)
			(end -0.299974 -0.150114)
			(stroke
				(width 0.1)
				(type default)
			)
			(layer "F.Fab")
		)
		(fp_line
			(start 0.299974 0.150114)
			(end -0.299974 0.150114)
			(stroke
				(width 0.1)
				(type default)
			)
			(layer "F.Fab")
		)
		(fp_line
			(start -0.299974 -0.150114)
			(end 0.299974 -0.150114)
			(stroke
				(width 0.1)
				(type default)
			)
			(layer "F.Fab")
		)
		(fp_line
			(start 0.299974 -0.150114)
			(end 0.299974 0.150114)
			(stroke
				(width 0.1)
				(type default)
			)
			(layer "F.Fab")
		)
		(pad "1" smd rect
			(at -0.2667 0 270)
			(size 0.3048 0.381)
			(layers "F.Cu" "F.Mask" "F.Paste")
			(net "P1V8_PLL0_PEX1")
		)
		(pad "2" smd rect
			(at 0.2667 0 270)
			(size 0.3048 0.381)
			(layers "F.Cu" "F.Mask" "F.Paste")
			(net "GND")
		)
	)
	(footprint ""
		(layer "F.Cu")
		(at 404.826724 -53.697124 -90)
		(property "Reference" "PC570"
			(at 0 0 270)
			(layer "F.SilkS")
			(hide yes)
			(effects
				(font
					(size 1.27 1.27)
				)
			)
		)
		(property "Value" ""
			(at 0 0 270)
			(layer "F.Fab")
			(effects
				(font
					(size 1.27 1.27)
				)
			)
		)
		(duplicate_pad_numbers_are_jumpers no)
		(fp_line
			(start -0.7874 0.4064)
			(end -0.7874 -0.4064)
			(stroke
				(width 0.1524)
				(type default)
			)
			(layer "F.SilkS")
		)
		(fp_line
			(start 0.7874 0.4064)
			(end -0.7874 0.4064)
			(stroke
				(width 0.1524)
				(type default)
			)
			(layer "F.SilkS")
		)
		(fp_line
			(start -0.7874 -0.4064)
			(end 0.7874 -0.4064)
			(stroke
				(width 0.1524)
				(type default)
			)
			(layer "F.SilkS")
		)
		(fp_line
			(start 0.7874 -0.4064)
			(end 0.7874 0.4064)
			(stroke
				(width 0.1524)
				(type default)
			)
			(layer "F.SilkS")
		)
		(fp_line
			(start -0.67945 0.3048)
			(end -0.67945 -0.305054)
			(stroke
				(width 0.1)
				(type default)
			)
			(layer "F.Fab")
		)
		(fp_line
			(start -0.12065 0.3048)
			(end -0.67945 0.3048)
			(stroke
				(width 0.1)
				(type default)
			)
			(layer "F.Fab")
		)
		(fp_line
			(start 0.120396 0.3048)
			(end 0.120396 0.2794)
			(stroke
				(width 0.1)
				(type default)
			)
			(layer "F.Fab")
		)
		(fp_line
			(start 0.67945 0.3048)
			(end 0.120396 0.3048)
			(stroke
				(width 0.1)
				(type default)
			)
			(layer "F.Fab")
		)
		(fp_line
			(start -0.12065 0.2794)
			(end -0.12065 0.3048)
			(stroke
				(width 0.1)
				(type default)
			)
			(layer "F.Fab")
		)
		(fp_line
			(start 0.120396 0.2794)
			(end -0.12065 0.2794)
			(stroke
				(width 0.1)
				(type default)
			)
			(layer "F.Fab")
		)
		(fp_line
			(start -0.12065 -0.2794)
			(end 0.12065 -0.2794)
			(stroke
				(width 0.1)
				(type default)
			)
			(layer "F.Fab")
		)
		(fp_line
			(start 0.12065 -0.2794)
			(end 0.12065 -0.3048)
			(stroke
				(width 0.1)
				(type default)
			)
			(layer "F.Fab")
		)
		(fp_line
			(start 0.12065 -0.3048)
			(end 0.67945 -0.3048)
			(stroke
				(width 0.1)
				(type default)
			)
			(layer "F.Fab")
		)
		(fp_line
			(start 0.67945 -0.3048)
			(end 0.67945 0.3048)
			(stroke
				(width 0.1)
				(type default)
			)
			(layer "F.Fab")
		)
		(fp_line
			(start -0.67945 -0.305054)
			(end -0.12065 -0.305054)
			(stroke
				(width 0.1)
				(type default)
			)
			(layer "F.Fab")
		)
		(fp_line
			(start -0.12065 -0.305054)
			(end -0.12065 -0.2794)
			(stroke
				(width 0.1)
				(type default)
			)
			(layer "F.Fab")
		)
		(pad "1" smd circle
			(at -0.40005 0 270)
			(size 0 0)
			(layers "F.Cu" "F.Mask" "F.Paste")
			(net "P3V3_AUX")
		)
		(pad "2" smd circle
			(at 0.40005 0 270)
			(size 0 0)
			(layers "F.Cu" "F.Mask" "F.Paste")
			(net "GND")
		)
	)
)
